(kicad_pcb
	(version 20260206)
	(generator "pcbnew")
	(generator_version "10.0")
	(general
		(thickness 1.6)
		(legacy_teardrops no)
	)
	(paper "A4")
	(title_block
		(title "04192023_DAF0TMB3IC0_F0TG_MB_C_brd_V02_OCP.brd")
		(comment 1 "Grand Teton / footprints 2226-2231 of 8354")
	)
	(layers
		(0 "F.Cu" signal "TOP")
		(4 "In1.Cu" signal "GND")
		(6 "In2.Cu" signal "IN1")
		(8 "In3.Cu" signal "GND1")
		(10 "In4.Cu" signal "IN2")
		(12 "In5.Cu" signal "GND2")
		(14 "In6.Cu" signal "IN3")
		(16 "In7.Cu" signal "GND3")
		(18 "In8.Cu" signal "VCC")
		(20 "In9.Cu" signal "VCC1")
		(22 "In10.Cu" signal "GND4")
		(24 "In11.Cu" signal "IN4")
		(26 "In12.Cu" signal "GND5")
		(28 "In13.Cu" signal "IN5")
		(30 "In14.Cu" signal "GND6")
		(32 "In15.Cu" signal "IN6")
		(34 "In16.Cu" signal "GND7")
		(2 "B.Cu" signal "BOTTOM")
		(9 "F.Adhes" user "F.Adhesive")
		(11 "B.Adhes" user "B.Adhesive")
		(13 "F.Paste" user "Package Geometry/Pastemask Top")
		(15 "B.Paste" user "Package Geometry/Pastemask Bottom")
		(5 "F.SilkS" user "Ref Des/Silkscreen Top")
		(7 "B.SilkS" user "Ref Des/Silkscreen Bottom")
		(1 "F.Mask" user "Board Geometry/Soldermask Top")
		(3 "B.Mask" user "Board Geometry/Soldermask Bottom")
		(17 "Dwgs.User" user "User.Drawings")
		(19 "Cmts.User" user "User.Comments")
		(21 "Eco1.User" user "User.Eco1")
		(23 "Eco2.User" user "User.Eco2")
		(25 "Edge.Cuts" user "Board Geometry/Outline")
		(27 "Margin" user)
		(31 "F.CrtYd" user "Package Geometry/Place Bound Top")
		(29 "B.CrtYd" user "Package Geometry/Place Bound Bottom")
		(35 "F.Fab" user "Ref Des/Assembly Top")
		(33 "B.Fab" user "Ref Des/Assembly Bottom")
	)
	(footprint ""
		(layer "F.Cu")
		(at 185.801 -92.674948 90)
		(property "Reference" "R6075"
			(at 0 0 90)
			(layer "F.SilkS")
			(hide yes)
			(effects
				(font
					(size 1.27 1.27)
				)
			)
		)
		(property "Value" ""
			(at 0 0 90)
			(layer "F.Fab")
			(effects
				(font
					(size 1.27 1.27)
				)
			)
		)
		(duplicate_pad_numbers_are_jumpers no)
		(fp_line
			(start 0.7874 -0.4064)
			(end 0.7874 0.4064)
			(stroke
				(width 0.1524)
				(type default)
			)
			(layer "F.SilkS")
		)
		(fp_line
			(start -0.7874 -0.4064)
			(end 0.7874 -0.4064)
			(stroke
				(width 0.1524)
				(type default)
			)
			(layer "F.SilkS")
		)
		(fp_line
			(start 0.7874 0.4064)
			(end -0.7874 0.4064)
			(stroke
				(width 0.1524)
				(type default)
			)
			(layer "F.SilkS")
		)
		(fp_line
			(start -0.7874 0.4064)
			(end -0.7874 -0.4064)
			(stroke
				(width 0.1524)
				(type default)
			)
			(layer "F.SilkS")
		)
		(fp_line
			(start -0.12065 -0.305054)
			(end -0.12065 -0.2794)
			(stroke
				(width 0.1)
				(type default)
			)
			(layer "F.Fab")
		)
		(fp_line
			(start -0.67945 -0.305054)
			(end -0.12065 -0.305054)
			(stroke
				(width 0.1)
				(type default)
			)
			(layer "F.Fab")
		)
		(fp_line
			(start 0.67945 -0.3048)
			(end 0.67945 0.3048)
			(stroke
				(width 0.1)
				(type default)
			)
			(layer "F.Fab")
		)
		(fp_line
			(start 0.12065 -0.3048)
			(end 0.67945 -0.3048)
			(stroke
				(width 0.1)
				(type default)
			)
			(layer "F.Fab")
		)
		(fp_line
			(start 0.12065 -0.2794)
			(end 0.12065 -0.3048)
			(stroke
				(width 0.1)
				(type default)
			)
			(layer "F.Fab")
		)
		(fp_line
			(start -0.12065 -0.2794)
			(end 0.12065 -0.2794)
			(stroke
				(width 0.1)
				(type default)
			)
			(layer "F.Fab")
		)
		(fp_line
			(start 0.120396 0.2794)
			(end -0.12065 0.2794)
			(stroke
				(width 0.1)
				(type default)
			)
			(layer "F.Fab")
		)
		(fp_line
			(start -0.12065 0.2794)
			(end -0.12065 0.3048)
			(stroke
				(width 0.1)
				(type default)
			)
			(layer "F.Fab")
		)
		(fp_line
			(start 0.67945 0.3048)
			(end 0.120396 0.3048)
			(stroke
				(width 0.1)
				(type default)
			)
			(layer "F.Fab")
		)
		(fp_line
			(start 0.120396 0.3048)
			(end 0.120396 0.2794)
			(stroke
				(width 0.1)
				(type default)
			)
			(layer "F.Fab")
		)
		(fp_line
			(start -0.12065 0.3048)
			(end -0.67945 0.3048)
			(stroke
				(width 0.1)
				(type default)
			)
			(layer "F.Fab")
		)
		(fp_line
			(start -0.67945 0.3048)
			(end -0.67945 -0.305054)
			(stroke
				(width 0.1)
				(type default)
			)
			(layer "F.Fab")
		)
		(pad "1" smd circle
			(at -0.40005 0 90)
			(size 0 0)
			(layers "F.Cu" "F.Mask" "F.Paste")
			(net "LED_HDD_ACTIVITY_B_N")
		)
		(pad "2" smd circle
			(at 0.40005 0 90)
			(size 0 0)
			(layers "F.Cu" "F.Mask" "F.Paste")
			(net "LED_HDD_ACTIVITY_B_PLD_N")
		)
	)
	(footprint ""
		(layer "F.Cu")
		(at 69.741034 -376.982228)
		(property "Reference" "C808"
			(at 0 0 0)
			(layer "F.SilkS")
			(hide yes)
			(effects
				(font
					(size 1.27 1.27)
				)
			)
		)
		(property "Value" ""
			(at 0 0 0)
			(layer "F.Fab")
			(effects
				(font
					(size 1.27 1.27)
				)
			)
		)
		(duplicate_pad_numbers_are_jumpers no)
		(fp_line
			(start -0.299974 -0.150114)
			(end 0.299974 -0.150114)
			(stroke
				(width 0.1)
				(type default)
			)
			(layer "F.Fab")
		)
		(fp_line
			(start -0.299974 0.150114)
			(end -0.299974 -0.150114)
			(stroke
				(width 0.1)
				(type default)
			)
			(layer "F.Fab")
		)
		(fp_line
			(start 0.299974 -0.150114)
			(end 0.299974 0.150114)
			(stroke
				(width 0.1)
				(type default)
			)
			(layer "F.Fab")
		)
		(fp_line
			(start 0.299974 0.150114)
			(end -0.299974 0.150114)
			(stroke
				(width 0.1)
				(type default)
			)
			(layer "F.Fab")
		)
		(pad "1" smd rect
			(at -0.2667 0)
			(size 0.3048 0.381)
			(layers "F.Cu" "F.Mask" "F.Paste")
			(net "P5E_CPU1_P0_TX_C_DN<14>")
		)
		(pad "2" smd rect
			(at 0.2667 0)
			(size 0.3048 0.381)
			(layers "F.Cu" "F.Mask" "F.Paste")
			(net "P5E_CPU1_P0_TX_DN<14>")
		)
	)
	(footprint ""
		(layer "F.Cu")
		(at 119.37365 -437.843422 -90)
		(property "Reference" "U257"
			(at 1.368044 1.755648 90)
			(unlocked yes)
			(layer "F.SilkS")
			(effects
				(font
					(size 0.7874 0.5842)
					(thickness 0.1524)
				)
				(justify left)
			)
		)
		(property "Value" ""
			(at 0 0 270)
			(layer "F.Fab")
			(effects
				(font
					(size 1.27 1.27)
				)
			)
		)
		(duplicate_pad_numbers_are_jumpers no)
		(fp_line
			(start -1.38176 1.100074)
			(end 1.38176 1.100074)
			(stroke
				(width 0.1524)
				(type default)
			)
			(layer "F.SilkS")
		)
		(fp_line
			(start 1.38176 1.100074)
			(end 1.38176 -1.100074)
			(stroke
				(width 0.1524)
				(type default)
			)
			(layer "F.SilkS")
		)
		(fp_line
			(start 0 -0.508)
			(end -0.592074 -1.100074)
			(stroke
				(width 0.1524)
				(type default)
			)
			(layer "F.SilkS")
		)
		(fp_line
			(start -1.38176 -1.100074)
			(end -1.38176 1.100074)
			(stroke
				(width 0.1524)
				(type default)
			)
			(layer "F.SilkS")
		)
		(fp_line
			(start -0.592074 -1.100074)
			(end -1.38176 -1.100074)
			(stroke
				(width 0.1524)
				(type default)
			)
			(layer "F.SilkS")
		)
		(fp_line
			(start 0.592074 -1.100074)
			(end 0 -0.508)
			(stroke
				(width 0.1524)
				(type default)
			)
			(layer "F.SilkS")
		)
		(fp_line
			(start 1.38176 -1.100074)
			(end 0.592074 -1.100074)
			(stroke
				(width 0.1524)
				(type default)
			)
			(layer "F.SilkS")
		)
		(fp_poly
			(pts
				(xy -1.998472 -1.387094) (xy -1.687068 -1.698498) (xy -1.531112 -1.231138)
			)
			(stroke
				(width 0)
				(type default)
			)
			(fill yes)
			(layer "F.SilkS")
		)
		(fp_line
			(start -0.674878 1.100074)
			(end 0.674878 1.100074)
			(stroke
				(width 0.1)
				(type default)
			)
			(layer "F.Fab")
		)
		(fp_line
			(start 0.674878 1.100074)
			(end 0.674878 -1.100074)
			(stroke
				(width 0.1)
				(type default)
			)
			(layer "F.Fab")
		)
		(fp_line
			(start -0.674878 -1.100074)
			(end -0.674878 1.100074)
			(stroke
				(width 0.1)
				(type default)
			)
			(layer "F.Fab")
		)
		(fp_line
			(start 0.674878 -1.100074)
			(end -0.674878 -1.100074)
			(stroke
				(width 0.1)
				(type default)
			)
			(layer "F.Fab")
		)
		(fp_poly
			(pts
				(xy -1.9431 -0.870204) (xy -1.50241 -0.649986) (xy -1.9431 -0.429768)
			)
			(stroke
				(width 0)
				(type default)
			)
			(fill yes)
			(layer "F.Fab")
		)
		(pad "1" smd rect
			(at -0.94996 -0.649986 180)
			(size 0.4318 0.6096)
			(layers "F.Cu" "F.Mask" "F.Paste")
			(net "GPU_FPGA_EROT_RECOV_N")
		)
		(pad "2" smd rect
			(at -0.94996 0 180)
			(size 0.4318 0.6096)
			(layers "F.Cu" "F.Mask" "F.Paste")
			(net "GND")
		)
		(pad "3" smd rect
			(at -0.94996 0.649986 180)
			(size 0.4318 0.6096)
			(layers "F.Cu" "F.Mask" "F.Paste")
			(net "GND")
		)
		(pad "4" smd rect
			(at 0.94996 0.649986 180)
			(size 0.4318 0.6096)
			(layers "F.Cu" "F.Mask" "F.Paste")
			(net "NC_U257_2Y")
		)
		(pad "5" smd rect
			(at 0.94996 0 180)
			(size 0.4318 0.6096)
			(layers "F.Cu" "F.Mask" "F.Paste")
			(net "P3V3_AUX")
		)
		(pad "6" smd rect
			(at 0.94996 -0.649986 180)
			(size 0.4318 0.6096)
			(layers "F.Cu" "F.Mask" "F.Paste")
			(net "GPU_FPGA_EROT_RECOV_BUF_R_N")
		)
	)
	(footprint ""
		(layer "F.Cu")
		(at 209.78622 -137.127488 180)
		(property "Reference" "U158"
			(at -0.62992 2.298192 0)
			(unlocked yes)
			(layer "F.SilkS")
			(effects
				(font
					(size 0.7874 0.5842)
					(thickness 0.1524)
				)
				(justify left)
			)
		)
		(property "Value" ""
			(at 0 0 180)
			(layer "F.Fab")
			(effects
				(font
					(size 1.27 1.27)
				)
			)
		)
		(duplicate_pad_numbers_are_jumpers no)
		(fp_line
			(start 1.603248 1.500124)
			(end -1.603248 1.500124)
			(stroke
				(width 0.1524)
				(type default)
			)
			(layer "F.SilkS")
		)
		(fp_line
			(start 1.603248 -1.500124)
			(end 1.603248 1.500124)
			(stroke
				(width 0.1524)
				(type default)
			)
			(layer "F.SilkS")
		)
		(fp_line
			(start -1.603248 1.500124)
			(end -1.603248 -1.500124)
			(stroke
				(width 0.1524)
				(type default)
			)
			(layer "F.SilkS")
		)
		(fp_line
			(start -1.603248 -1.500124)
			(end 1.603248 -1.500124)
			(stroke
				(width 0.1524)
				(type default)
			)
			(layer "F.SilkS")
		)
		(fp_line
			(start 1.249934 0.219964)
			(end 1.249934 -0.219964)
			(stroke
				(width 0.1)
				(type default)
			)
			(layer "F.Fab")
		)
		(fp_line
			(start 1.249934 -0.219964)
			(end 0.700024 -0.219964)
			(stroke
				(width 0.1)
				(type default)
			)
			(layer "F.Fab")
		)
		(fp_line
			(start 0.700024 1.500124)
			(end 0.700024 0.219964)
			(stroke
				(width 0.1)
				(type default)
			)
			(layer "F.Fab")
		)
		(fp_line
			(start 0.700024 0.219964)
			(end 1.249934 0.219964)
			(stroke
				(width 0.1)
				(type default)
			)
			(layer "F.Fab")
		)
		(fp_line
			(start 0.700024 -0.219964)
			(end 0.700024 -1.500124)
			(stroke
				(width 0.1)
				(type default)
			)
			(layer "F.Fab")
		)
		(fp_line
			(start 0.700024 -1.500124)
			(end -0.700024 -1.500124)
			(stroke
				(width 0.1)
				(type default)
			)
			(layer "F.Fab")
		)
		(fp_line
			(start -0.6985 0.729996)
			(end -1.249934 0.729996)
			(stroke
				(width 0.1)
				(type default)
			)
			(layer "F.Fab")
		)
		(fp_line
			(start -0.6985 -0.729996)
			(end -0.6985 0.729996)
			(stroke
				(width 0.1)
				(type default)
			)
			(layer "F.Fab")
		)
		(fp_line
			(start -0.700024 1.500124)
			(end 0.700024 1.500124)
			(stroke
				(width 0.1)
				(type default)
			)
			(layer "F.Fab")
		)
		(fp_line
			(start -0.700024 1.169924)
			(end -0.700024 1.500124)
			(stroke
				(width 0.1)
				(type default)
			)
			(layer "F.Fab")
		)
		(fp_line
			(start -0.700024 -1.169924)
			(end -1.249934 -1.169924)
			(stroke
				(width 0.1)
				(type default)
			)
			(layer "F.Fab")
		)
		(fp_line
			(start -0.700024 -1.500124)
			(end -0.700024 -1.169924)
			(stroke
				(width 0.1)
				(type default)
			)
			(layer "F.Fab")
		)
		(fp_line
			(start -1.249934 1.169924)
			(end -0.700024 1.169924)
			(stroke
				(width 0.1)
				(type default)
			)
			(layer "F.Fab")
		)
		(fp_line
			(start -1.249934 0.729996)
			(end -1.249934 1.169924)
			(stroke
				(width 0.1)
				(type default)
			)
			(layer "F.Fab")
		)
		(fp_line
			(start -1.249934 -0.729996)
			(end -0.6985 -0.729996)
			(stroke
				(width 0.1)
				(type default)
			)
			(layer "F.Fab")
		)
		(fp_line
			(start -1.249934 -1.169924)
			(end -1.249934 -0.729996)
			(stroke
				(width 0.1)
				(type default)
			)
			(layer "F.Fab")
		)
		(fp_rect
			(start 0.700024 -1.500124)
			(end -0.700024 1.500124)
			(stroke
				(width 0)
				(type default)
			)
			(fill no)
			(layer "F.Fab")
		)
		(pad "D" smd rect
			(at 0.999998 0 90)
			(size 0.8128 0.9144)
			(layers "F.Cu" "F.Mask" "F.Paste")
			(net "FM_P12V_HSC_EN_N")
		)
		(pad "G" smd rect
			(at -0.999998 -0.94996 90)
			(size 0.8128 0.9144)
			(layers "F.Cu" "F.Mask" "F.Paste")
			(net "FM_P12V_HSC_EN_R")
		)
		(pad "S" smd rect
			(at -0.999998 0.94996 90)
			(size 0.8128 0.9144)
			(layers "F.Cu" "F.Mask" "F.Paste")
			(net "GND")
		)
	)
	(footprint ""
		(layer "F.Cu")
		(at 39.95039 -426.563536 180)
		(property "Reference" "C6007"
			(at 0 0 180)
			(layer "F.SilkS")
			(hide yes)
			(effects
				(font
					(size 1.27 1.27)
				)
			)
		)
		(property "Value" ""
			(at 0 0 180)
			(layer "F.Fab")
			(effects
				(font
					(size 1.27 1.27)
				)
			)
		)
		(duplicate_pad_numbers_are_jumpers no)
		(fp_line
			(start 0.7874 0.4064)
			(end -0.7874 0.4064)
			(stroke
				(width 0.1524)
				(type default)
			)
			(layer "F.SilkS")
		)
		(fp_line
			(start 0.7874 -0.275336)
			(end 0.7874 0.4064)
			(stroke
				(width 0.1524)
				(type default)
			)
			(layer "F.SilkS")
		)
		(fp_line
			(start -0.7874 -0.4064)
			(end -0.35941 -0.4064)
			(stroke
				(width 0.1524)
				(type default)
			)
			(layer "F.SilkS")
		)
		(fp_line
			(start 0.6858 0.3048)
			(end 0.1016 0.3048)
			(stroke
				(width 0.1)
				(type default)
			)
			(layer "F.Fab")
		)
		(fp_line
			(start 0.6858 -0.3048)
			(end 0.6858 0.3048)
			(stroke
				(width 0.1)
				(type default)
			)
			(layer "F.Fab")
		)
		(fp_line
			(start 0.1016 0.3048)
			(end 0.1016 0.2794)
			(stroke
				(width 0.1)
				(type default)
			)
			(layer "F.Fab")
		)
		(fp_line
			(start 0.1016 0.2794)
			(end -0.1016 0.2794)
			(stroke
				(width 0.1)
				(type default)
			)
			(layer "F.Fab")
		)
		(fp_line
			(start 0.1016 -0.2794)
			(end 0.1016 -0.3048)
			(stroke
				(width 0.1)
				(type default)
			)
			(layer "F.Fab")
		)
		(fp_line
			(start 0.1016 -0.3048)
			(end 0.6858 -0.3048)
			(stroke
				(width 0.1)
				(type default)
			)
			(layer "F.Fab")
		)
		(fp_line
			(start -0.1016 0.3048)
			(end -0.6858 0.3048)
			(stroke
				(width 0.1)
				(type default)
			)
			(layer "F.Fab")
		)
		(fp_line
			(start -0.1016 0.2794)
			(end -0.1016 0.3048)
			(stroke
				(width 0.1)
				(type default)
			)
			(layer "F.Fab")
		)
		(fp_line
			(start -0.1016 -0.2794)
			(end 0.1016 -0.2794)
			(stroke
				(width 0.1)
				(type default)
			)
			(layer "F.Fab")
		)
		(fp_line
			(start -0.1016 -0.3048)
			(end -0.1016 -0.2794)
			(stroke
				(width 0.1)
				(type default)
			)
			(layer "F.Fab")
		)
		(fp_line
			(start -0.6858 0.3048)
			(end -0.6858 -0.3048)
			(stroke
				(width 0.1)
				(type default)
			)
			(layer "F.Fab")
		)
		(fp_line
			(start -0.6858 -0.3048)
			(end -0.1016 -0.3048)
			(stroke
				(width 0.1)
				(type default)
			)
			(layer "F.Fab")
		)
		(pad "1" smd rect
			(at -0.40005 0)
			(size 0.4572 0.508)
			(layers "F.Cu" "F.Mask" "F.Paste")
			(net "P2E_MB_BMC_RX_BUF2_C_DP<0>")
		)
		(pad "2" smd rect
			(at 0.40005 0)
			(size 0.4572 0.508)
			(layers "F.Cu" "F.Mask" "F.Paste")
			(net "P2E_MB_BMC_RX_BUF_DP<0>")
		)
	)
	(footprint ""
		(layer "F.Cu")
		(at 101.421946 -54.882034 90)
		(property "Reference" "R6321"
			(at 0 0 90)
			(layer "F.SilkS")
			(hide yes)
			(effects
				(font
					(size 1.27 1.27)
				)
			)
		)
		(property "Value" ""
			(at 0 0 90)
			(layer "F.Fab")
			(effects
				(font
					(size 1.27 1.27)
				)
			)
		)
		(duplicate_pad_numbers_are_jumpers no)
		(fp_line
			(start 0.7874 -0.4064)
			(end 0.7874 0.4064)
			(stroke
				(width 0.1524)
				(type default)
			)
			(layer "F.SilkS")
		)
		(fp_line
			(start -0.7874 -0.4064)
			(end 0.7874 -0.4064)
			(stroke
				(width 0.1524)
				(type default)
			)
			(layer "F.SilkS")
		)
		(fp_line
			(start 0.7874 0.4064)
			(end -0.7874 0.4064)
			(stroke
				(width 0.1524)
				(type default)
			)
			(layer "F.SilkS")
		)
		(fp_line
			(start -0.7874 0.4064)
			(end -0.7874 -0.4064)
			(stroke
				(width 0.1524)
				(type default)
			)
			(layer "F.SilkS")
		)
		(fp_line
			(start -0.12065 -0.305054)
			(end -0.12065 -0.2794)
			(stroke
				(width 0.1)
				(type default)
			)
			(layer "F.Fab")
		)
		(fp_line
			(start -0.67945 -0.305054)
			(end -0.12065 -0.305054)
			(stroke
				(width 0.1)
				(type default)
			)
			(layer "F.Fab")
		)
		(fp_line
			(start 0.67945 -0.3048)
			(end 0.67945 0.3048)
			(stroke
				(width 0.1)
				(type default)
			)
			(layer "F.Fab")
		)
		(fp_line
			(start 0.12065 -0.3048)
			(end 0.67945 -0.3048)
			(stroke
				(width 0.1)
				(type default)
			)
			(layer "F.Fab")
		)
		(fp_line
			(start 0.12065 -0.2794)
			(end 0.12065 -0.3048)
			(stroke
				(width 0.1)
				(type default)
			)
			(layer "F.Fab")
		)
		(fp_line
			(start -0.12065 -0.2794)
			(end 0.12065 -0.2794)
			(stroke
				(width 0.1)
				(type default)
			)
			(layer "F.Fab")
		)
		(fp_line
			(start 0.120396 0.2794)
			(end -0.12065 0.2794)
			(stroke
				(width 0.1)
				(type default)
			)
			(layer "F.Fab")
		)
		(fp_line
			(start -0.12065 0.2794)
			(end -0.12065 0.3048)
			(stroke
				(width 0.1)
				(type default)
			)
			(layer "F.Fab")
		)
		(fp_line
			(start 0.67945 0.3048)
			(end 0.120396 0.3048)
			(stroke
				(width 0.1)
				(type default)
			)
			(layer "F.Fab")
		)
		(fp_line
			(start 0.120396 0.3048)
			(end 0.120396 0.2794)
			(stroke
				(width 0.1)
				(type default)
			)
			(layer "F.Fab")
		)
		(fp_line
			(start -0.12065 0.3048)
			(end -0.67945 0.3048)
			(stroke
				(width 0.1)
				(type default)
			)
			(layer "F.Fab")
		)
		(fp_line
			(start -0.67945 0.3048)
			(end -0.67945 -0.305054)
			(stroke
				(width 0.1)
				(type default)
			)
			(layer "F.Fab")
		)
		(pad "1" smd circle
			(at -0.40005 0 90)
			(size 0 0)
			(layers "F.Cu" "F.Mask" "F.Paste")
			(net "USB_HUB2_MRP_RESET_N")
		)
		(pad "2" smd circle
			(at 0.40005 0 90)
			(size 0 0)
			(layers "F.Cu" "F.Mask" "F.Paste")
			(net "GND")
		)
	)
)
